(kicad_pcb
	(version 20260206)
	(generator "pcbnew")
	(generator_version "10.0")
	(general
		(thickness 1.6)
		(legacy_teardrops no)
	)
	(paper "A4")
	(title_block
		(title "04192023_DAF0TMB3IC0_F0TG_MB_C_brd_V02_OCP.brd")
		(comment 1 "Grand Teton / footprints 982-988 of 8354")
	)
	(layers
		(0 "F.Cu" signal "TOP")
		(4 "In1.Cu" signal "GND")
		(6 "In2.Cu" signal "IN1")
		(8 "In3.Cu" signal "GND1")
		(10 "In4.Cu" signal "IN2")
		(12 "In5.Cu" signal "GND2")
		(14 "In6.Cu" signal "IN3")
		(16 "In7.Cu" signal "GND3")
		(18 "In8.Cu" signal "VCC")
		(20 "In9.Cu" signal "VCC1")
		(22 "In10.Cu" signal "GND4")
		(24 "In11.Cu" signal "IN4")
		(26 "In12.Cu" signal "GND5")
		(28 "In13.Cu" signal "IN5")
		(30 "In14.Cu" signal "GND6")
		(32 "In15.Cu" signal "IN6")
		(34 "In16.Cu" signal "GND7")
		(2 "B.Cu" signal "BOTTOM")
		(9 "F.Adhes" user "F.Adhesive")
		(11 "B.Adhes" user "B.Adhesive")
		(13 "F.Paste" user "Package Geometry/Pastemask Top")
		(15 "B.Paste" user "Package Geometry/Pastemask Bottom")
		(5 "F.SilkS" user "Ref Des/Silkscreen Top")
		(7 "B.SilkS" user "Ref Des/Silkscreen Bottom")
		(1 "F.Mask" user "Board Geometry/Soldermask Top")
		(3 "B.Mask" user "Board Geometry/Soldermask Bottom")
		(17 "Dwgs.User" user "User.Drawings")
		(19 "Cmts.User" user "User.Comments")
		(21 "Eco1.User" user "User.Eco1")
		(23 "Eco2.User" user "User.Eco2")
		(25 "Edge.Cuts" user "Board Geometry/Outline")
		(27 "Margin" user)
		(31 "F.CrtYd" user "Package Geometry/Place Bound Top")
		(29 "B.CrtYd" user "Package Geometry/Place Bound Bottom")
		(35 "F.Fab" user "Ref Des/Assembly Top")
		(33 "B.Fab" user "Ref Des/Assembly Bottom")
	)
	(footprint ""
		(layer "F.Cu")
		(at 136.10717 -156.532834 90)
		(property "Reference" "PC347_SOP1_3"
			(at 0 0 90)
			(layer "F.SilkS")
			(hide yes)
			(effects
				(font
					(size 1.27 1.27)
				)
			)
		)
		(property "Value" ""
			(at 0 0 90)
			(layer "F.Fab")
			(effects
				(font
					(size 1.27 1.27)
				)
			)
		)
		(duplicate_pad_numbers_are_jumpers no)
		(fp_line
			(start 0.7874 -0.4064)
			(end 0.7874 0.4064)
			(stroke
				(width 0.1524)
				(type default)
			)
			(layer "F.SilkS")
		)
		(fp_line
			(start -0.7874 -0.4064)
			(end 0.7874 -0.4064)
			(stroke
				(width 0.1524)
				(type default)
			)
			(layer "F.SilkS")
		)
		(fp_line
			(start 0.7874 0.4064)
			(end -0.7874 0.4064)
			(stroke
				(width 0.1524)
				(type default)
			)
			(layer "F.SilkS")
		)
		(fp_line
			(start -0.7874 0.4064)
			(end -0.7874 -0.4064)
			(stroke
				(width 0.1524)
				(type default)
			)
			(layer "F.SilkS")
		)
		(fp_line
			(start -0.12065 -0.305054)
			(end -0.12065 -0.2794)
			(stroke
				(width 0.1)
				(type default)
			)
			(layer "F.Fab")
		)
		(fp_line
			(start -0.67945 -0.305054)
			(end -0.12065 -0.305054)
			(stroke
				(width 0.1)
				(type default)
			)
			(layer "F.Fab")
		)
		(fp_line
			(start 0.67945 -0.3048)
			(end 0.67945 0.3048)
			(stroke
				(width 0.1)
				(type default)
			)
			(layer "F.Fab")
		)
		(fp_line
			(start 0.12065 -0.3048)
			(end 0.67945 -0.3048)
			(stroke
				(width 0.1)
				(type default)
			)
			(layer "F.Fab")
		)
		(fp_line
			(start 0.12065 -0.2794)
			(end 0.12065 -0.3048)
			(stroke
				(width 0.1)
				(type default)
			)
			(layer "F.Fab")
		)
		(fp_line
			(start -0.12065 -0.2794)
			(end 0.12065 -0.2794)
			(stroke
				(width 0.1)
				(type default)
			)
			(layer "F.Fab")
		)
		(fp_line
			(start 0.120396 0.2794)
			(end -0.12065 0.2794)
			(stroke
				(width 0.1)
				(type default)
			)
			(layer "F.Fab")
		)
		(fp_line
			(start -0.12065 0.2794)
			(end -0.12065 0.3048)
			(stroke
				(width 0.1)
				(type default)
			)
			(layer "F.Fab")
		)
		(fp_line
			(start 0.67945 0.3048)
			(end 0.120396 0.3048)
			(stroke
				(width 0.1)
				(type default)
			)
			(layer "F.Fab")
		)
		(fp_line
			(start 0.120396 0.3048)
			(end 0.120396 0.2794)
			(stroke
				(width 0.1)
				(type default)
			)
			(layer "F.Fab")
		)
		(fp_line
			(start -0.12065 0.3048)
			(end -0.67945 0.3048)
			(stroke
				(width 0.1)
				(type default)
			)
			(layer "F.Fab")
		)
		(fp_line
			(start -0.67945 0.3048)
			(end -0.67945 -0.305054)
			(stroke
				(width 0.1)
				(type default)
			)
			(layer "F.Fab")
		)
		(pad "1" smd circle
			(at -0.40005 0 90)
			(size 0 0)
			(layers "F.Cu" "F.Mask" "F.Paste")
			(net "PVDDCR_CPU0_P1_PVCC")
		)
		(pad "2" smd circle
			(at 0.40005 0 90)
			(size 0 0)
			(layers "F.Cu" "F.Mask" "F.Paste")
			(net "GND")
		)
	)
	(footprint ""
		(layer "F.Cu")
		(at 150.502366 -55.188358)
		(property "Reference" "R3621"
			(at 0 0 0)
			(layer "F.SilkS")
			(hide yes)
			(effects
				(font
					(size 1.27 1.27)
				)
			)
		)
		(property "Value" ""
			(at 0 0 0)
			(layer "F.Fab")
			(effects
				(font
					(size 1.27 1.27)
				)
			)
		)
		(duplicate_pad_numbers_are_jumpers no)
		(fp_line
			(start -0.7874 -0.4064)
			(end 0.7874 -0.4064)
			(stroke
				(width 0.1524)
				(type default)
			)
			(layer "F.SilkS")
		)
		(fp_line
			(start -0.7874 0.4064)
			(end -0.7874 -0.4064)
			(stroke
				(width 0.1524)
				(type default)
			)
			(layer "F.SilkS")
		)
		(fp_line
			(start 0.7874 -0.4064)
			(end 0.7874 0.4064)
			(stroke
				(width 0.1524)
				(type default)
			)
			(layer "F.SilkS")
		)
		(fp_line
			(start 0.7874 0.4064)
			(end -0.7874 0.4064)
			(stroke
				(width 0.1524)
				(type default)
			)
			(layer "F.SilkS")
		)
		(fp_line
			(start -0.67945 -0.305054)
			(end -0.12065 -0.305054)
			(stroke
				(width 0.1)
				(type default)
			)
			(layer "F.Fab")
		)
		(fp_line
			(start -0.67945 0.3048)
			(end -0.67945 -0.305054)
			(stroke
				(width 0.1)
				(type default)
			)
			(layer "F.Fab")
		)
		(fp_line
			(start -0.12065 -0.305054)
			(end -0.12065 -0.2794)
			(stroke
				(width 0.1)
				(type default)
			)
			(layer "F.Fab")
		)
		(fp_line
			(start -0.12065 -0.2794)
			(end 0.12065 -0.2794)
			(stroke
				(width 0.1)
				(type default)
			)
			(layer "F.Fab")
		)
		(fp_line
			(start -0.12065 0.2794)
			(end -0.12065 0.3048)
			(stroke
				(width 0.1)
				(type default)
			)
			(layer "F.Fab")
		)
		(fp_line
			(start -0.12065 0.3048)
			(end -0.67945 0.3048)
			(stroke
				(width 0.1)
				(type default)
			)
			(layer "F.Fab")
		)
		(fp_line
			(start 0.120396 0.2794)
			(end -0.12065 0.2794)
			(stroke
				(width 0.1)
				(type default)
			)
			(layer "F.Fab")
		)
		(fp_line
			(start 0.120396 0.3048)
			(end 0.120396 0.2794)
			(stroke
				(width 0.1)
				(type default)
			)
			(layer "F.Fab")
		)
		(fp_line
			(start 0.12065 -0.3048)
			(end 0.67945 -0.3048)
			(stroke
				(width 0.1)
				(type default)
			)
			(layer "F.Fab")
		)
		(fp_line
			(start 0.12065 -0.2794)
			(end 0.12065 -0.3048)
			(stroke
				(width 0.1)
				(type default)
			)
			(layer "F.Fab")
		)
		(fp_line
			(start 0.67945 -0.3048)
			(end 0.67945 0.3048)
			(stroke
				(width 0.1)
				(type default)
			)
			(layer "F.Fab")
		)
		(fp_line
			(start 0.67945 0.3048)
			(end 0.120396 0.3048)
			(stroke
				(width 0.1)
				(type default)
			)
			(layer "F.Fab")
		)
		(pad "1" smd circle
			(at -0.40005 0)
			(size 0 0)
			(layers "F.Cu" "F.Mask" "F.Paste")
			(net "P3V3_AUX")
		)
		(pad "2" smd circle
			(at 0.40005 0)
			(size 0 0)
			(layers "F.Cu" "F.Mask" "F.Paste")
			(net "INA230_4_A0")
		)
	)
	(footprint ""
		(layer "F.Cu")
		(at 217.047826 -125.62459)
		(property "Reference" "R6826"
			(at 0 0 0)
			(layer "F.SilkS")
			(hide yes)
			(effects
				(font
					(size 1.27 1.27)
				)
			)
		)
		(property "Value" ""
			(at 0 0 0)
			(layer "F.Fab")
			(effects
				(font
					(size 1.27 1.27)
				)
			)
		)
		(duplicate_pad_numbers_are_jumpers no)
		(fp_line
			(start -0.7874 -0.4064)
			(end 0.7874 -0.4064)
			(stroke
				(width 0.1524)
				(type default)
			)
			(layer "F.SilkS")
		)
		(fp_line
			(start -0.7874 0.4064)
			(end -0.7874 -0.4064)
			(stroke
				(width 0.1524)
				(type default)
			)
			(layer "F.SilkS")
		)
		(fp_line
			(start 0.7874 -0.4064)
			(end 0.7874 0.4064)
			(stroke
				(width 0.1524)
				(type default)
			)
			(layer "F.SilkS")
		)
		(fp_line
			(start 0.7874 0.4064)
			(end -0.7874 0.4064)
			(stroke
				(width 0.1524)
				(type default)
			)
			(layer "F.SilkS")
		)
		(fp_line
			(start -0.67945 -0.305054)
			(end -0.12065 -0.305054)
			(stroke
				(width 0.1)
				(type default)
			)
			(layer "F.Fab")
		)
		(fp_line
			(start -0.67945 0.3048)
			(end -0.67945 -0.305054)
			(stroke
				(width 0.1)
				(type default)
			)
			(layer "F.Fab")
		)
		(fp_line
			(start -0.12065 -0.305054)
			(end -0.12065 -0.2794)
			(stroke
				(width 0.1)
				(type default)
			)
			(layer "F.Fab")
		)
		(fp_line
			(start -0.12065 -0.2794)
			(end 0.12065 -0.2794)
			(stroke
				(width 0.1)
				(type default)
			)
			(layer "F.Fab")
		)
		(fp_line
			(start -0.12065 0.2794)
			(end -0.12065 0.3048)
			(stroke
				(width 0.1)
				(type default)
			)
			(layer "F.Fab")
		)
		(fp_line
			(start -0.12065 0.3048)
			(end -0.67945 0.3048)
			(stroke
				(width 0.1)
				(type default)
			)
			(layer "F.Fab")
		)
		(fp_line
			(start 0.120396 0.2794)
			(end -0.12065 0.2794)
			(stroke
				(width 0.1)
				(type default)
			)
			(layer "F.Fab")
		)
		(fp_line
			(start 0.120396 0.3048)
			(end 0.120396 0.2794)
			(stroke
				(width 0.1)
				(type default)
			)
			(layer "F.Fab")
		)
		(fp_line
			(start 0.12065 -0.3048)
			(end 0.67945 -0.3048)
			(stroke
				(width 0.1)
				(type default)
			)
			(layer "F.Fab")
		)
		(fp_line
			(start 0.12065 -0.2794)
			(end 0.12065 -0.3048)
			(stroke
				(width 0.1)
				(type default)
			)
			(layer "F.Fab")
		)
		(fp_line
			(start 0.67945 -0.3048)
			(end 0.67945 0.3048)
			(stroke
				(width 0.1)
				(type default)
			)
			(layer "F.Fab")
		)
		(fp_line
			(start 0.67945 0.3048)
			(end 0.120396 0.3048)
			(stroke
				(width 0.1)
				(type default)
			)
			(layer "F.Fab")
		)
		(pad "1" smd circle
			(at -0.40005 0)
			(size 0 0)
			(layers "F.Cu" "F.Mask" "F.Paste")
			(net "RST_RT_CPU0_P3_RESET_R2_N")
		)
		(pad "2" smd circle
			(at 0.40005 0)
			(size 0 0)
			(layers "F.Cu" "F.Mask" "F.Paste")
			(net "RST_RT_CPU0_P3_RESET_R_N")
		)
	)
	(footprint ""
		(layer "F.Cu")
		(at 283.216858 -405.066754 -90)
		(property "Reference" "R354"
			(at 0 0 270)
			(layer "F.SilkS")
			(hide yes)
			(effects
				(font
					(size 1.27 1.27)
				)
			)
		)
		(property "Value" ""
			(at 0 0 270)
			(layer "F.Fab")
			(effects
				(font
					(size 1.27 1.27)
				)
			)
		)
		(duplicate_pad_numbers_are_jumpers no)
		(fp_line
			(start -0.7874 0.4064)
			(end -0.7874 -0.4064)
			(stroke
				(width 0.1524)
				(type default)
			)
			(layer "F.SilkS")
		)
		(fp_line
			(start 0.7874 0.4064)
			(end -0.7874 0.4064)
			(stroke
				(width 0.1524)
				(type default)
			)
			(layer "F.SilkS")
		)
		(fp_line
			(start -0.7874 -0.4064)
			(end 0.7874 -0.4064)
			(stroke
				(width 0.1524)
				(type default)
			)
			(layer "F.SilkS")
		)
		(fp_line
			(start 0.7874 -0.4064)
			(end 0.7874 0.4064)
			(stroke
				(width 0.1524)
				(type default)
			)
			(layer "F.SilkS")
		)
		(fp_line
			(start -0.67945 0.3048)
			(end -0.67945 -0.305054)
			(stroke
				(width 0.1)
				(type default)
			)
			(layer "F.Fab")
		)
		(fp_line
			(start -0.12065 0.3048)
			(end -0.67945 0.3048)
			(stroke
				(width 0.1)
				(type default)
			)
			(layer "F.Fab")
		)
		(fp_line
			(start 0.120396 0.3048)
			(end 0.120396 0.2794)
			(stroke
				(width 0.1)
				(type default)
			)
			(layer "F.Fab")
		)
		(fp_line
			(start 0.67945 0.3048)
			(end 0.120396 0.3048)
			(stroke
				(width 0.1)
				(type default)
			)
			(layer "F.Fab")
		)
		(fp_line
			(start -0.12065 0.2794)
			(end -0.12065 0.3048)
			(stroke
				(width 0.1)
				(type default)
			)
			(layer "F.Fab")
		)
		(fp_line
			(start 0.120396 0.2794)
			(end -0.12065 0.2794)
			(stroke
				(width 0.1)
				(type default)
			)
			(layer "F.Fab")
		)
		(fp_line
			(start -0.12065 -0.2794)
			(end 0.12065 -0.2794)
			(stroke
				(width 0.1)
				(type default)
			)
			(layer "F.Fab")
		)
		(fp_line
			(start 0.12065 -0.2794)
			(end 0.12065 -0.3048)
			(stroke
				(width 0.1)
				(type default)
			)
			(layer "F.Fab")
		)
		(fp_line
			(start 0.12065 -0.3048)
			(end 0.67945 -0.3048)
			(stroke
				(width 0.1)
				(type default)
			)
			(layer "F.Fab")
		)
		(fp_line
			(start 0.67945 -0.3048)
			(end 0.67945 0.3048)
			(stroke
				(width 0.1)
				(type default)
			)
			(layer "F.Fab")
		)
		(fp_line
			(start -0.67945 -0.305054)
			(end -0.12065 -0.305054)
			(stroke
				(width 0.1)
				(type default)
			)
			(layer "F.Fab")
		)
		(fp_line
			(start -0.12065 -0.305054)
			(end -0.12065 -0.2794)
			(stroke
				(width 0.1)
				(type default)
			)
			(layer "F.Fab")
		)
		(pad "1" smd circle
			(at -0.40005 0 270)
			(size 0 0)
			(layers "F.Cu" "F.Mask" "F.Paste")
			(net "P3V3_AUX")
		)
		(pad "2" smd circle
			(at 0.40005 0 270)
			(size 0 0)
			(layers "F.Cu" "F.Mask" "F.Paste")
			(net "P12V_HSC_T_CRIT_R_N")
		)
	)
	(footprint ""
		(layer "F.Cu")
		(at 41.5544 -390.652)
		(property "Reference" "R728"
			(at 0 0 0)
			(layer "F.SilkS")
			(hide yes)
			(effects
				(font
					(size 1.27 1.27)
				)
			)
		)
		(property "Value" ""
			(at 0 0 0)
			(layer "F.Fab")
			(effects
				(font
					(size 1.27 1.27)
				)
			)
		)
		(duplicate_pad_numbers_are_jumpers no)
		(fp_line
			(start -0.32512 -0.175006)
			(end 0.32512 -0.175006)
			(stroke
				(width 0.1)
				(type default)
			)
			(layer "F.Fab")
		)
		(fp_line
			(start -0.32512 0.175006)
			(end -0.32512 -0.175006)
			(stroke
				(width 0.1)
				(type default)
			)
			(layer "F.Fab")
		)
		(fp_line
			(start 0.32512 -0.175006)
			(end 0.32512 0.175006)
			(stroke
				(width 0.1)
				(type default)
			)
			(layer "F.Fab")
		)
		(fp_line
			(start 0.32512 0.175006)
			(end -0.32512 0.175006)
			(stroke
				(width 0.1)
				(type default)
			)
			(layer "F.Fab")
		)
		(pad "1" smd rect
			(at -0.2667 0)
			(size 0.3048 0.381)
			(layers "F.Cu" "F.Mask" "F.Paste")
			(net "MODE_RT_CPU1_P0")
		)
		(pad "2" smd rect
			(at 0.2667 0 180)
			(size 0.3048 0.381)
			(layers "F.Cu" "F.Mask" "F.Paste")
			(net "GND")
		)
	)
	(footprint ""
		(layer "F.Cu")
		(at 391.291318 -75.391264 180)
		(property "Reference" "R1355"
			(at 0 0 180)
			(layer "F.SilkS")
			(hide yes)
			(effects
				(font
					(size 1.27 1.27)
				)
			)
		)
		(property "Value" ""
			(at 0 0 180)
			(layer "F.Fab")
			(effects
				(font
					(size 1.27 1.27)
				)
			)
		)
		(duplicate_pad_numbers_are_jumpers no)
		(fp_line
			(start 0.7874 0.4064)
			(end -0.7874 0.4064)
			(stroke
				(width 0.1524)
				(type default)
			)
			(layer "F.SilkS")
		)
		(fp_line
			(start 0.7874 -0.4064)
			(end 0.7874 0.4064)
			(stroke
				(width 0.1524)
				(type default)
			)
			(layer "F.SilkS")
		)
		(fp_line
			(start -0.7874 0.4064)
			(end -0.7874 -0.4064)
			(stroke
				(width 0.1524)
				(type default)
			)
			(layer "F.SilkS")
		)
		(fp_line
			(start -0.7874 -0.4064)
			(end 0.7874 -0.4064)
			(stroke
				(width 0.1524)
				(type default)
			)
			(layer "F.SilkS")
		)
		(fp_line
			(start 0.67945 0.3048)
			(end 0.120396 0.3048)
			(stroke
				(width 0.1)
				(type default)
			)
			(layer "F.Fab")
		)
		(fp_line
			(start 0.67945 -0.3048)
			(end 0.67945 0.3048)
			(stroke
				(width 0.1)
				(type default)
			)
			(layer "F.Fab")
		)
		(fp_line
			(start 0.12065 -0.2794)
			(end 0.12065 -0.3048)
			(stroke
				(width 0.1)
				(type default)
			)
			(layer "F.Fab")
		)
		(fp_line
			(start 0.12065 -0.3048)
			(end 0.67945 -0.3048)
			(stroke
				(width 0.1)
				(type default)
			)
			(layer "F.Fab")
		)
		(fp_line
			(start 0.120396 0.3048)
			(end 0.120396 0.2794)
			(stroke
				(width 0.1)
				(type default)
			)
			(layer "F.Fab")
		)
		(fp_line
			(start 0.120396 0.2794)
			(end -0.12065 0.2794)
			(stroke
				(width 0.1)
				(type default)
			)
			(layer "F.Fab")
		)
		(fp_line
			(start -0.12065 0.3048)
			(end -0.67945 0.3048)
			(stroke
				(width 0.1)
				(type default)
			)
			(layer "F.Fab")
		)
		(fp_line
			(start -0.12065 0.2794)
			(end -0.12065 0.3048)
			(stroke
				(width 0.1)
				(type default)
			)
			(layer "F.Fab")
		)
		(fp_line
			(start -0.12065 -0.2794)
			(end 0.12065 -0.2794)
			(stroke
				(width 0.1)
				(type default)
			)
			(layer "F.Fab")
		)
		(fp_line
			(start -0.12065 -0.305054)
			(end -0.12065 -0.2794)
			(stroke
				(width 0.1)
				(type default)
			)
			(layer "F.Fab")
		)
		(fp_line
			(start -0.67945 0.3048)
			(end -0.67945 -0.305054)
			(stroke
				(width 0.1)
				(type default)
			)
			(layer "F.Fab")
		)
		(fp_line
			(start -0.67945 -0.305054)
			(end -0.12065 -0.305054)
			(stroke
				(width 0.1)
				(type default)
			)
			(layer "F.Fab")
		)
		(pad "1" smd circle
			(at -0.40005 0 180)
			(size 0 0)
			(layers "F.Cu" "F.Mask" "F.Paste")
			(net "INA230_6_A0")
		)
		(pad "2" smd circle
			(at 0.40005 0 180)
			(size 0 0)
			(layers "F.Cu" "F.Mask" "F.Paste")
			(net "SMB_INA230_6_3V3AUX_SDA_R1")
		)
	)
	(footprint ""
		(layer "F.Cu")
		(at 85.961728 -184.478168 -90)
		(property "Reference" "PR485"
			(at 0 0 270)
			(layer "F.SilkS")
			(hide yes)
			(effects
				(font
					(size 1.27 1.27)
				)
			)
		)
		(property "Value" ""
			(at 0 0 270)
			(layer "F.Fab")
			(effects
				(font
					(size 1.27 1.27)
				)
			)
		)
		(duplicate_pad_numbers_are_jumpers no)
		(fp_line
			(start -0.7874 0.4064)
			(end -0.7874 -0.4064)
			(stroke
				(width 0.1524)
				(type default)
			)
			(layer "F.SilkS")
		)
		(fp_line
			(start 0.7874 0.4064)
			(end -0.7874 0.4064)
			(stroke
				(width 0.1524)
				(type default)
			)
			(layer "F.SilkS")
		)
		(fp_line
			(start -0.7874 -0.4064)
			(end 0.7874 -0.4064)
			(stroke
				(width 0.1524)
				(type default)
			)
			(layer "F.SilkS")
		)
		(fp_line
			(start 0.7874 -0.4064)
			(end 0.7874 0.4064)
			(stroke
				(width 0.1524)
				(type default)
			)
			(layer "F.SilkS")
		)
		(fp_line
			(start -0.67945 0.3048)
			(end -0.67945 -0.305054)
			(stroke
				(width 0.1)
				(type default)
			)
			(layer "F.Fab")
		)
		(fp_line
			(start -0.12065 0.3048)
			(end -0.67945 0.3048)
			(stroke
				(width 0.1)
				(type default)
			)
			(layer "F.Fab")
		)
		(fp_line
			(start 0.120396 0.3048)
			(end 0.120396 0.2794)
			(stroke
				(width 0.1)
				(type default)
			)
			(layer "F.Fab")
		)
		(fp_line
			(start 0.67945 0.3048)
			(end 0.120396 0.3048)
			(stroke
				(width 0.1)
				(type default)
			)
			(layer "F.Fab")
		)
		(fp_line
			(start -0.12065 0.2794)
			(end -0.12065 0.3048)
			(stroke
				(width 0.1)
				(type default)
			)
			(layer "F.Fab")
		)
		(fp_line
			(start 0.120396 0.2794)
			(end -0.12065 0.2794)
			(stroke
				(width 0.1)
				(type default)
			)
			(layer "F.Fab")
		)
		(fp_line
			(start -0.12065 -0.2794)
			(end 0.12065 -0.2794)
			(stroke
				(width 0.1)
				(type default)
			)
			(layer "F.Fab")
		)
		(fp_line
			(start 0.12065 -0.2794)
			(end 0.12065 -0.3048)
			(stroke
				(width 0.1)
				(type default)
			)
			(layer "F.Fab")
		)
		(fp_line
			(start 0.12065 -0.3048)
			(end 0.67945 -0.3048)
			(stroke
				(width 0.1)
				(type default)
			)
			(layer "F.Fab")
		)
		(fp_line
			(start 0.67945 -0.3048)
			(end 0.67945 0.3048)
			(stroke
				(width 0.1)
				(type default)
			)
			(layer "F.Fab")
		)
		(fp_line
			(start -0.67945 -0.305054)
			(end -0.12065 -0.305054)
			(stroke
				(width 0.1)
				(type default)
			)
			(layer "F.Fab")
		)
		(fp_line
			(start -0.12065 -0.305054)
			(end -0.12065 -0.2794)
			(stroke
				(width 0.1)
				(type default)
			)
			(layer "F.Fab")
		)
		(pad "1" smd circle
			(at -0.40005 0 270)
			(size 0 0)
			(layers "F.Cu" "F.Mask" "F.Paste")
			(net "SW_PVDDCR_CPU0_P1_SW1_RC")
		)
		(pad "2" smd circle
			(at 0.40005 0 270)
			(size 0 0)
			(layers "F.Cu" "F.Mask" "F.Paste")
			(net "GND")
		)
	)
)
